FILE_TYPE=LIBRARY_PARTS;
TIME=' Created/Modified on Fri Aug 20 09:19:25 2010' ;
primitive 'METR3904G';
  pin
    '1':
      PIN_NUMBER='(B)';
      INPUT_LOAD='(-0.01,0.01)';
    '2':
      PIN_NUMBER='(E)';
      INPUT_LOAD='(-0.01,0.01)';
      OUTPUT_LOAD='(1.0,-1.0)';
      BIDIRECTIONAL='TRUE';
    '3':
      PIN_NUMBER='(C)';
      INPUT_LOAD='(-0.01,0.01)';
      OUTPUT_LOAD='(1.0,-1.0)';
      BIDIRECTIONAL='TRUE';
  end_pin;
  body
    CLASS='DISCRETE';
    PART_NAME='METR3904G';
    PHYS_DES_PREFIX='Q';
  end_body;
end_primitive;
END.
